FILE_TYPE = CONNECTIVITY;
{Allegro Design Entry HDL 17.4-2019 S026 (4007227) 1/17/2022}
"PAGE_NUMBER" = 250;
0"NC";
END.
